(kicad_pcb
	(version 20260206)
	(generator "pcbnew")
	(generator_version "10.0")
	(general
		(thickness 1.6)
		(legacy_teardrops no)
	)
	(paper "A4")
	(title_block
		(title "04192023_DAF0TMB3IC0_F0TG_MB_C_brd_V02_OCP.brd")
		(comment 1 "Grand Teton / footprints 2128-2133 of 8354")
	)
	(layers
		(0 "F.Cu" signal "TOP")
		(4 "In1.Cu" signal "GND")
		(6 "In2.Cu" signal "IN1")
		(8 "In3.Cu" signal "GND1")
		(10 "In4.Cu" signal "IN2")
		(12 "In5.Cu" signal "GND2")
		(14 "In6.Cu" signal "IN3")
		(16 "In7.Cu" signal "GND3")
		(18 "In8.Cu" signal "VCC")
		(20 "In9.Cu" signal "VCC1")
		(22 "In10.Cu" signal "GND4")
		(24 "In11.Cu" signal "IN4")
		(26 "In12.Cu" signal "GND5")
		(28 "In13.Cu" signal "IN5")
		(30 "In14.Cu" signal "GND6")
		(32 "In15.Cu" signal "IN6")
		(34 "In16.Cu" signal "GND7")
		(2 "B.Cu" signal "BOTTOM")
		(9 "F.Adhes" user "F.Adhesive")
		(11 "B.Adhes" user "B.Adhesive")
		(13 "F.Paste" user "Package Geometry/Pastemask Top")
		(15 "B.Paste" user "Package Geometry/Pastemask Bottom")
		(5 "F.SilkS" user "Ref Des/Silkscreen Top")
		(7 "B.SilkS" user "Ref Des/Silkscreen Bottom")
		(1 "F.Mask" user "Board Geometry/Soldermask Top")
		(3 "B.Mask" user "Board Geometry/Soldermask Bottom")
		(17 "Dwgs.User" user "User.Drawings")
		(19 "Cmts.User" user "User.Comments")
		(21 "Eco1.User" user "User.Eco1")
		(23 "Eco2.User" user "User.Eco2")
		(25 "Edge.Cuts" user "Board Geometry/Outline")
		(27 "Margin" user)
		(31 "F.CrtYd" user "Package Geometry/Place Bound Top")
		(29 "B.CrtYd" user "Package Geometry/Place Bound Bottom")
		(35 "F.Fab" user "Ref Des/Assembly Top")
		(33 "B.Fab" user "Ref Des/Assembly Bottom")
	)
	(footprint ""
		(layer "F.Cu")
		(at 201.041 -128.778)
		(property "Reference" "R8021"
			(at 0 0 0)
			(layer "F.SilkS")
			(hide yes)
			(effects
				(font
					(size 1.27 1.27)
				)
			)
		)
		(property "Value" ""
			(at 0 0 0)
			(layer "F.Fab")
			(effects
				(font
					(size 1.27 1.27)
				)
			)
		)
		(duplicate_pad_numbers_are_jumpers no)
		(fp_line
			(start -0.7874 -0.4064)
			(end 0.7874 -0.4064)
			(stroke
				(width 0.1524)
				(type default)
			)
			(layer "F.SilkS")
		)
		(fp_line
			(start -0.7874 0.4064)
			(end -0.7874 -0.4064)
			(stroke
				(width 0.1524)
				(type default)
			)
			(layer "F.SilkS")
		)
		(fp_line
			(start 0.7874 -0.4064)
			(end 0.7874 0.4064)
			(stroke
				(width 0.1524)
				(type default)
			)
			(layer "F.SilkS")
		)
		(fp_line
			(start 0.7874 0.4064)
			(end -0.7874 0.4064)
			(stroke
				(width 0.1524)
				(type default)
			)
			(layer "F.SilkS")
		)
		(fp_line
			(start -0.67945 -0.305054)
			(end -0.12065 -0.305054)
			(stroke
				(width 0.1)
				(type default)
			)
			(layer "F.Fab")
		)
		(fp_line
			(start -0.67945 0.3048)
			(end -0.67945 -0.305054)
			(stroke
				(width 0.1)
				(type default)
			)
			(layer "F.Fab")
		)
		(fp_line
			(start -0.12065 -0.305054)
			(end -0.12065 -0.2794)
			(stroke
				(width 0.1)
				(type default)
			)
			(layer "F.Fab")
		)
		(fp_line
			(start -0.12065 -0.2794)
			(end 0.12065 -0.2794)
			(stroke
				(width 0.1)
				(type default)
			)
			(layer "F.Fab")
		)
		(fp_line
			(start -0.12065 0.2794)
			(end -0.12065 0.3048)
			(stroke
				(width 0.1)
				(type default)
			)
			(layer "F.Fab")
		)
		(fp_line
			(start -0.12065 0.3048)
			(end -0.67945 0.3048)
			(stroke
				(width 0.1)
				(type default)
			)
			(layer "F.Fab")
		)
		(fp_line
			(start 0.120396 0.2794)
			(end -0.12065 0.2794)
			(stroke
				(width 0.1)
				(type default)
			)
			(layer "F.Fab")
		)
		(fp_line
			(start 0.120396 0.3048)
			(end 0.120396 0.2794)
			(stroke
				(width 0.1)
				(type default)
			)
			(layer "F.Fab")
		)
		(fp_line
			(start 0.12065 -0.3048)
			(end 0.67945 -0.3048)
			(stroke
				(width 0.1)
				(type default)
			)
			(layer "F.Fab")
		)
		(fp_line
			(start 0.12065 -0.2794)
			(end 0.12065 -0.3048)
			(stroke
				(width 0.1)
				(type default)
			)
			(layer "F.Fab")
		)
		(fp_line
			(start 0.67945 -0.3048)
			(end 0.67945 0.3048)
			(stroke
				(width 0.1)
				(type default)
			)
			(layer "F.Fab")
		)
		(fp_line
			(start 0.67945 0.3048)
			(end 0.120396 0.3048)
			(stroke
				(width 0.1)
				(type default)
			)
			(layer "F.Fab")
		)
		(pad "1" smd circle
			(at -0.40005 0)
			(size 0 0)
			(layers "F.Cu" "F.Mask" "F.Paste")
			(net "FM_JTAG_BMC_OE")
		)
		(pad "2" smd circle
			(at 0.40005 0)
			(size 0 0)
			(layers "F.Cu" "F.Mask" "F.Paste")
			(net "FM_JTAG_BMC_R_OE")
		)
	)
	(footprint ""
		(layer "F.Cu")
		(at 191.897 -100.294948 90)
		(property "Reference" "R264"
			(at 0 0 90)
			(layer "F.SilkS")
			(hide yes)
			(effects
				(font
					(size 1.27 1.27)
				)
			)
		)
		(property "Value" ""
			(at 0 0 90)
			(layer "F.Fab")
			(effects
				(font
					(size 1.27 1.27)
				)
			)
		)
		(duplicate_pad_numbers_are_jumpers no)
		(fp_line
			(start 0.7874 -0.4064)
			(end 0.7874 0.4064)
			(stroke
				(width 0.1524)
				(type default)
			)
			(layer "F.SilkS")
		)
		(fp_line
			(start -0.7874 -0.4064)
			(end 0.7874 -0.4064)
			(stroke
				(width 0.1524)
				(type default)
			)
			(layer "F.SilkS")
		)
		(fp_line
			(start 0.7874 0.4064)
			(end -0.7874 0.4064)
			(stroke
				(width 0.1524)
				(type default)
			)
			(layer "F.SilkS")
		)
		(fp_line
			(start -0.7874 0.4064)
			(end -0.7874 -0.4064)
			(stroke
				(width 0.1524)
				(type default)
			)
			(layer "F.SilkS")
		)
		(fp_line
			(start -0.12065 -0.305054)
			(end -0.12065 -0.2794)
			(stroke
				(width 0.1)
				(type default)
			)
			(layer "F.Fab")
		)
		(fp_line
			(start -0.67945 -0.305054)
			(end -0.12065 -0.305054)
			(stroke
				(width 0.1)
				(type default)
			)
			(layer "F.Fab")
		)
		(fp_line
			(start 0.67945 -0.3048)
			(end 0.67945 0.3048)
			(stroke
				(width 0.1)
				(type default)
			)
			(layer "F.Fab")
		)
		(fp_line
			(start 0.12065 -0.3048)
			(end 0.67945 -0.3048)
			(stroke
				(width 0.1)
				(type default)
			)
			(layer "F.Fab")
		)
		(fp_line
			(start 0.12065 -0.2794)
			(end 0.12065 -0.3048)
			(stroke
				(width 0.1)
				(type default)
			)
			(layer "F.Fab")
		)
		(fp_line
			(start -0.12065 -0.2794)
			(end 0.12065 -0.2794)
			(stroke
				(width 0.1)
				(type default)
			)
			(layer "F.Fab")
		)
		(fp_line
			(start 0.120396 0.2794)
			(end -0.12065 0.2794)
			(stroke
				(width 0.1)
				(type default)
			)
			(layer "F.Fab")
		)
		(fp_line
			(start -0.12065 0.2794)
			(end -0.12065 0.3048)
			(stroke
				(width 0.1)
				(type default)
			)
			(layer "F.Fab")
		)
		(fp_line
			(start 0.67945 0.3048)
			(end 0.120396 0.3048)
			(stroke
				(width 0.1)
				(type default)
			)
			(layer "F.Fab")
		)
		(fp_line
			(start 0.120396 0.3048)
			(end 0.120396 0.2794)
			(stroke
				(width 0.1)
				(type default)
			)
			(layer "F.Fab")
		)
		(fp_line
			(start -0.12065 0.3048)
			(end -0.67945 0.3048)
			(stroke
				(width 0.1)
				(type default)
			)
			(layer "F.Fab")
		)
		(fp_line
			(start -0.67945 0.3048)
			(end -0.67945 -0.305054)
			(stroke
				(width 0.1)
				(type default)
			)
			(layer "F.Fab")
		)
		(pad "1" smd circle
			(at -0.40005 0 90)
			(size 0 0)
			(layers "F.Cu" "F.Mask" "F.Paste")
			(net "CPU1_CORETYPE2")
		)
		(pad "2" smd circle
			(at 0.40005 0 90)
			(size 0 0)
			(layers "F.Cu" "F.Mask" "F.Paste")
			(net "FM_CPU1_CORETYPE2")
		)
	)
	(footprint ""
		(layer "F.Cu")
		(at 229.87 -283.917898 180)
		(property "Reference" "PC6520"
			(at 0 0 180)
			(layer "F.SilkS")
			(hide yes)
			(effects
				(font
					(size 1.27 1.27)
				)
			)
		)
		(property "Value" ""
			(at 0 0 180)
			(layer "F.Fab")
			(effects
				(font
					(size 1.27 1.27)
				)
			)
		)
		(duplicate_pad_numbers_are_jumpers no)
		(fp_line
			(start 1.524 0.762)
			(end -1.524 0.762)
			(stroke
				(width 0.1524)
				(type default)
			)
			(layer "F.SilkS")
		)
		(fp_line
			(start 1.524 -0.762)
			(end 1.524 0.762)
			(stroke
				(width 0.1524)
				(type default)
			)
			(layer "F.SilkS")
		)
		(fp_line
			(start -1.524 0.762)
			(end -1.524 -0.762)
			(stroke
				(width 0.1524)
				(type default)
			)
			(layer "F.SilkS")
		)
		(fp_line
			(start -1.524 -0.762)
			(end 1.524 -0.762)
			(stroke
				(width 0.1524)
				(type default)
			)
			(layer "F.SilkS")
		)
		(fp_line
			(start 1.1049 0.724916)
			(end 1.1049 -0.724916)
			(stroke
				(width 0.1)
				(type default)
			)
			(layer "F.Fab")
		)
		(fp_line
			(start 1.1049 -0.724916)
			(end -1.1049 -0.724916)
			(stroke
				(width 0.1)
				(type default)
			)
			(layer "F.Fab")
		)
		(fp_line
			(start -1.1049 0.724916)
			(end 1.1049 0.724916)
			(stroke
				(width 0.1)
				(type default)
			)
			(layer "F.Fab")
		)
		(fp_line
			(start -1.1049 -0.724916)
			(end -1.1049 0.724916)
			(stroke
				(width 0.1)
				(type default)
			)
			(layer "F.Fab")
		)
		(pad "1" smd rect
			(at -0.889 0)
			(size 1.016 1.27)
			(layers "F.Cu" "F.Mask" "F.Paste")
			(net "SW_P12V_AUX_P1V8_RETIMER_CPU1_FLT")
		)
		(pad "2" smd rect
			(at 0.889 0)
			(size 1.016 1.27)
			(layers "F.Cu" "F.Mask" "F.Paste")
			(net "GND")
		)
	)
	(footprint ""
		(layer "F.Cu")
		(at 194.218306 -332.744572 -90)
		(property "Reference" "PC530"
			(at -4.24434 17.347692 90)
			(unlocked yes)
			(layer "F.SilkS")
			(effects
				(font
					(size 0.7874 0.5842)
					(thickness 0.1524)
				)
				(justify left)
			)
		)
		(property "Value" ""
			(at 0 0 270)
			(layer "F.Fab")
			(effects
				(font
					(size 1.27 1.27)
				)
			)
		)
		(duplicate_pad_numbers_are_jumpers no)
		(fp_line
			(start -1.988058 2.750058)
			(end 2.750058 2.750058)
			(stroke
				(width 0.1524)
				(type default)
			)
			(layer "F.SilkS")
		)
		(fp_line
			(start 2.750058 2.750058)
			(end 2.750058 0.9398)
			(stroke
				(width 0.1524)
				(type default)
			)
			(layer "F.SilkS")
		)
		(fp_line
			(start -2.750058 1.988058)
			(end -1.988058 2.750058)
			(stroke
				(width 0.1524)
				(type default)
			)
			(layer "F.SilkS")
		)
		(fp_line
			(start -2.750058 0.9398)
			(end -2.750058 1.988058)
			(stroke
				(width 0.1524)
				(type default)
			)
			(layer "F.SilkS")
		)
		(fp_line
			(start 2.750058 -0.9398)
			(end 2.750058 -2.750058)
			(stroke
				(width 0.1524)
				(type default)
			)
			(layer "F.SilkS")
		)
		(fp_line
			(start -2.750058 -1.988058)
			(end -2.750058 -0.9398)
			(stroke
				(width 0.1524)
				(type default)
			)
			(layer "F.SilkS")
		)
		(fp_line
			(start -1.988058 -2.750058)
			(end -2.750058 -1.988058)
			(stroke
				(width 0.1524)
				(type default)
			)
			(layer "F.SilkS")
		)
		(fp_line
			(start 2.750058 -2.750058)
			(end -1.988058 -2.750058)
			(stroke
				(width 0.1524)
				(type default)
			)
			(layer "F.SilkS")
		)
		(fp_line
			(start -2.750058 2.750058)
			(end 2.750058 2.750058)
			(stroke
				(width 0.1)
				(type default)
			)
			(layer "F.Fab")
		)
		(fp_line
			(start 2.750058 2.750058)
			(end 2.750058 -2.750058)
			(stroke
				(width 0.1)
				(type default)
			)
			(layer "F.Fab")
		)
		(fp_line
			(start -2.750058 -2.750058)
			(end -2.750058 2.750058)
			(stroke
				(width 0.1)
				(type default)
			)
			(layer "F.Fab")
		)
		(fp_line
			(start 2.750058 -2.750058)
			(end -2.750058 -2.750058)
			(stroke
				(width 0.1)
				(type default)
			)
			(layer "F.Fab")
		)
		(pad "1" smd rect
			(at -2.199894 0)
			(size 1.6002 3.0226)
			(layers "F.Cu" "F.Mask" "F.Paste")
			(net "PVDD11_S3_P1")
		)
		(pad "2" smd rect
			(at 2.199894 0)
			(size 1.6002 3.0226)
			(layers "F.Cu" "F.Mask" "F.Paste")
			(net "GND")
		)
	)
	(footprint ""
		(layer "F.Cu")
		(at 101.555296 -422.43248 90)
		(property "Reference" "R4187"
			(at 0 0 90)
			(layer "F.SilkS")
			(hide yes)
			(effects
				(font
					(size 1.27 1.27)
				)
			)
		)
		(property "Value" ""
			(at 0 0 90)
			(layer "F.Fab")
			(effects
				(font
					(size 1.27 1.27)
				)
			)
		)
		(duplicate_pad_numbers_are_jumpers no)
		(fp_line
			(start 0.7874 -0.4064)
			(end 0.7874 0.4064)
			(stroke
				(width 0.1524)
				(type default)
			)
			(layer "F.SilkS")
		)
		(fp_line
			(start -0.7874 -0.4064)
			(end 0.7874 -0.4064)
			(stroke
				(width 0.1524)
				(type default)
			)
			(layer "F.SilkS")
		)
		(fp_line
			(start 0.7874 0.4064)
			(end -0.7874 0.4064)
			(stroke
				(width 0.1524)
				(type default)
			)
			(layer "F.SilkS")
		)
		(fp_line
			(start -0.7874 0.4064)
			(end -0.7874 -0.4064)
			(stroke
				(width 0.1524)
				(type default)
			)
			(layer "F.SilkS")
		)
		(fp_line
			(start -0.12065 -0.305054)
			(end -0.12065 -0.2794)
			(stroke
				(width 0.1)
				(type default)
			)
			(layer "F.Fab")
		)
		(fp_line
			(start -0.67945 -0.305054)
			(end -0.12065 -0.305054)
			(stroke
				(width 0.1)
				(type default)
			)
			(layer "F.Fab")
		)
		(fp_line
			(start 0.67945 -0.3048)
			(end 0.67945 0.3048)
			(stroke
				(width 0.1)
				(type default)
			)
			(layer "F.Fab")
		)
		(fp_line
			(start 0.12065 -0.3048)
			(end 0.67945 -0.3048)
			(stroke
				(width 0.1)
				(type default)
			)
			(layer "F.Fab")
		)
		(fp_line
			(start 0.12065 -0.2794)
			(end 0.12065 -0.3048)
			(stroke
				(width 0.1)
				(type default)
			)
			(layer "F.Fab")
		)
		(fp_line
			(start -0.12065 -0.2794)
			(end 0.12065 -0.2794)
			(stroke
				(width 0.1)
				(type default)
			)
			(layer "F.Fab")
		)
		(fp_line
			(start 0.120396 0.2794)
			(end -0.12065 0.2794)
			(stroke
				(width 0.1)
				(type default)
			)
			(layer "F.Fab")
		)
		(fp_line
			(start -0.12065 0.2794)
			(end -0.12065 0.3048)
			(stroke
				(width 0.1)
				(type default)
			)
			(layer "F.Fab")
		)
		(fp_line
			(start 0.67945 0.3048)
			(end 0.120396 0.3048)
			(stroke
				(width 0.1)
				(type default)
			)
			(layer "F.Fab")
		)
		(fp_line
			(start 0.120396 0.3048)
			(end 0.120396 0.2794)
			(stroke
				(width 0.1)
				(type default)
			)
			(layer "F.Fab")
		)
		(fp_line
			(start -0.12065 0.3048)
			(end -0.67945 0.3048)
			(stroke
				(width 0.1)
				(type default)
			)
			(layer "F.Fab")
		)
		(fp_line
			(start -0.67945 0.3048)
			(end -0.67945 -0.305054)
			(stroke
				(width 0.1)
				(type default)
			)
			(layer "F.Fab")
		)
		(pad "1" smd circle
			(at -0.40005 0 90)
			(size 0 0)
			(layers "F.Cu" "F.Mask" "F.Paste")
			(net "U272_2_ADD2")
		)
		(pad "2" smd circle
			(at 0.40005 0 90)
			(size 0 0)
			(layers "F.Cu" "F.Mask" "F.Paste")
			(net "GND")
		)
	)
	(footprint ""
		(layer "F.Cu")
		(at 180.528468 -50.060098)
		(property "Reference" "C1100"
			(at 0 0 0)
			(layer "F.SilkS")
			(hide yes)
			(effects
				(font
					(size 1.27 1.27)
				)
			)
		)
		(property "Value" ""
			(at 0 0 0)
			(layer "F.Fab")
			(effects
				(font
					(size 1.27 1.27)
				)
			)
		)
		(duplicate_pad_numbers_are_jumpers no)
		(fp_line
			(start -0.299974 -0.150114)
			(end 0.299974 -0.150114)
			(stroke
				(width 0.1)
				(type default)
			)
			(layer "F.Fab")
		)
		(fp_line
			(start -0.299974 0.150114)
			(end -0.299974 -0.150114)
			(stroke
				(width 0.1)
				(type default)
			)
			(layer "F.Fab")
		)
		(fp_line
			(start 0.299974 -0.150114)
			(end 0.299974 0.150114)
			(stroke
				(width 0.1)
				(type default)
			)
			(layer "F.Fab")
		)
		(fp_line
			(start 0.299974 0.150114)
			(end -0.299974 0.150114)
			(stroke
				(width 0.1)
				(type default)
			)
			(layer "F.Fab")
		)
		(pad "1" smd rect
			(at -0.2667 0)
			(size 0.3048 0.381)
			(layers "F.Cu" "F.Mask" "F.Paste")
			(net "P3E_CPU1_P4_TX_C_DP<2>")
		)
		(pad "2" smd rect
			(at 0.2667 0)
			(size 0.3048 0.381)
			(layers "F.Cu" "F.Mask" "F.Paste")
			(net "P3E_CPU1_P4_TX_DP<2>")
		)
	)
)
